(kicad_pcb
	(version 20240108)
	(generator "pcbnew")
	(generator_version "8.0")
	(general
		(thickness 1.62)
		(legacy_teardrops no)
	)
	(paper "A4")
	(title_block
		(title "Jetson Orin Baseboard")
		(date "2025-03-12")
		(rev "1.3.4")
		(company "Antmicro Ltd")
		(comment 1 "www.antmicro.com")
		(comment 9 "footprints 233-236 of 677")
	)
	(layers
		(0 "F.Cu" signal)
		(1 "In1.Cu" signal)
		(2 "In2.Cu" signal)
		(3 "In3.Cu" signal)
		(4 "In4.Cu" jumper)
		(5 "In5.Cu" signal)
		(6 "In6.Cu" signal)
		(31 "B.Cu" signal)
		(32 "B.Adhes" user "B.Adhesive")
		(33 "F.Adhes" user "F.Adhesive")
		(34 "B.Paste" user)
		(35 "F.Paste" user)
		(36 "B.SilkS" user "B.Silkscreen")
		(37 "F.SilkS" user "F.Silkscreen")
		(38 "B.Mask" user)
		(39 "F.Mask" user)
		(40 "Dwgs.User" user "User.Drawings")
		(41 "Cmts.User" user "User.Comments")
		(42 "Eco1.User" user "User.Eco1")
		(43 "Eco2.User" user "User.Eco2")
		(44 "Edge.Cuts" user)
		(45 "Margin" user)
		(46 "B.CrtYd" user "B.Courtyard")
		(47 "F.CrtYd" user "F.Courtyard")
		(48 "B.Fab" user)
		(49 "F.Fab" user)
	)
	(footprint "antmicro-footprints:R_0402_1005Metric"
		(layer "F.Cu")
		(at 40.415 104.991 -90)
		(descr "Resistor SMD 0402")
		(tags "resistor SMD 0402")
		(property "Reference" "R241"
			(at 1.409 0.415 -90)
			(layer "F.SilkS")
			(effects
				(font
					(size 0.7 0.7)
					(thickness 0.15)
				)
				(justify left bottom)
			)
		)
		(property "Value" "R_0R_0402"
			(at 0 1.4 -90)
			(layer "F.Fab")
			(effects
				(font
					(size 0.7 0.7)
					(thickness 0.15)
				)
				(justify left bottom)
			)
		)
		(property "Footprint" "antmicro-footprints:R_0402_1005Metric"
			(at 0 0 -90)
			(layer "F.Fab")
			(hide yes)
			(effects
				(font
					(size 1.27 1.27)
					(thickness 0.15)
				)
			)
		)
		(property "Datasheet" "https://industrial.panasonic.com/cdbs/www-data/pdf/RDA0000/AOA0000C301.pdf"
			(at 0 0 -90)
			(layer "F.Fab")
			(hide yes)
			(effects
				(font
					(size 1.27 1.27)
					(thickness 0.15)
				)
			)
		)
		(property "Author" "Antmicro"
			(at -64.576 145.406 0)
			(layer "F.Fab")
			(hide yes)
			(effects
				(font
					(size 1 1)
					(thickness 0.15)
				)
			)
		)
		(property "Current" "1A"
			(at -64.576 145.406 0)
			(layer "F.Fab")
			(hide yes)
			(effects
				(font
					(size 1 1)
					(thickness 0.15)
				)
			)
		)
		(property "License" "Apache-2.0"
			(at -64.576 145.406 0)
			(layer "F.Fab")
			(hide yes)
			(effects
				(font
					(size 1 1)
					(thickness 0.15)
				)
			)
		)
		(property "MPN" "ERJ2GE0R00X"
			(at -64.576 145.406 0)
			(layer "F.Fab")
			(hide yes)
			(effects
				(font
					(size 1 1)
					(thickness 0.15)
				)
			)
		)
		(property "Manufacturer" "Panasonic"
			(at -64.576 145.406 0)
			(layer "F.Fab")
			(hide yes)
			(effects
				(font
					(size 1 1)
					(thickness 0.15)
				)
			)
		)
		(property "Tolerance" ""
			(at -64.576 145.406 0)
			(layer "F.Fab")
			(hide yes)
			(effects
				(font
					(size 1 1)
					(thickness 0.15)
				)
			)
		)
		(property "Val" "0R"
			(at -64.576 145.406 0)
			(layer "F.Fab")
			(hide yes)
			(effects
				(font
					(size 1 1)
					(thickness 0.15)
				)
			)
		)
		(sheetname "Ethernet")
		(sheetfile "ethernet.kicad_sch")
		(attr smd exclude_from_pos_files exclude_from_bom dnp)
		(fp_rect
			(start -0.925 -0.47)
			(end 0.925 0.47)
			(stroke
				(width 0.05)
				(type default)
			)
			(fill none)
			(layer "F.CrtYd")
		)
		(fp_rect
			(start -0.5 -0.25)
			(end 0.5 0.25)
			(stroke
				(width 0.15)
				(type solid)
			)
			(fill none)
			(layer "F.Fab")
		)
		(fp_text user "${REFERENCE}"
			(at -0.95 3.168 -90)
			(layer "F.Fab")
			(hide yes)
			(effects
				(font
					(size 0.7 0.7)
					(thickness 0.15)
				)
				(justify left bottom)
			)
		)
		(fp_text user "Author: Antmicro"
			(at -0.95 4.169 -90)
			(layer "F.Fab")
			(hide yes)
			(effects
				(font
					(size 0.7 0.7)
					(thickness 0.15)
				)
				(justify left bottom)
			)
		)
		(fp_text user "License: Apache-2.0"
			(at -0.95 5.169 -90)
			(layer "F.Fab")
			(hide yes)
			(effects
				(font
					(size 0.7 0.7)
					(thickness 0.15)
				)
				(justify left bottom)
			)
		)
		(pad "1" smd roundrect
			(at -0.48 0 270)
			(size 0.59 0.64)
			(layers "F.Cu" "F.Paste" "F.Mask")
			(roundrect_rratio 0.25)
			(net 650 "/Ethernet/ULS-12_CTRL")
			(pintype "passive")
		)
		(pad "2" smd roundrect
			(at 0.48 0 270)
			(size 0.59 0.64)
			(layers "F.Cu" "F.Paste" "F.Mask")
			(roundrect_rratio 0.25)
			(net 127 "/Ethernet/POE_ACTIVE")
			(pintype "passive")
		)
	)
	(footprint "antmicro-footprints:USON-10_2.5x1mm_P0.5mm"
		(layer "F.Cu")
		(at 110.55 116.178749 90)
		(descr "USON-10 2.5x1mm_ Pitch 0.5mm")
		(tags "USON-10 2.5x1mm Pitch 0.5mm")
		(property "Reference" "U20"
			(at 0.878749 -1.1 180)
			(layer "F.SilkS")
			(effects
				(font
					(size 0.7 0.7)
					(thickness 0.15)
				)
				(justify left bottom)
			)
		)
		(property "Value" "TPD4E05U06QDQARQ1"
			(at 0.018 2.499 90)
			(layer "F.Fab")
			(effects
				(font
					(size 0.7 0.7)
					(thickness 0.15)
				)
				(justify left bottom)
			)
		)
		(property "Footprint" "antmicro-footprints:USON-10_2.5x1mm_P0.5mm"
			(at 0 0 90)
			(layer "F.Fab")
			(hide yes)
			(effects
				(font
					(size 1.27 1.27)
					(thickness 0.15)
				)
			)
		)
		(property "Datasheet" "https://www.ti.com/lit/ds/symlink/tpd4e05u06-q1.pdf?HQS=dis-mous-null-mousermode-dsf-pf-null-wwe&ts=1663591265741&ref_url=https%253A%252F%252Fwww.mouser.com%252F"
			(at 0 0 90)
			(layer "F.Fab")
			(hide yes)
			(effects
				(font
					(size 1.27 1.27)
					(thickness 0.15)
				)
			)
		)
		(property "Author" "Antmicro"
			(at 226.728749 5.628749 0)
			(layer "F.Fab")
			(hide yes)
			(effects
				(font
					(size 1 1)
					(thickness 0.15)
				)
			)
		)
		(property "License" "Apache-2.0"
			(at 226.728749 5.628749 0)
			(layer "F.Fab")
			(hide yes)
			(effects
				(font
					(size 1 1)
					(thickness 0.15)
				)
			)
		)
		(property "MPN" "TPD4E05U06QDQARQ1"
			(at 226.728749 5.628749 0)
			(layer "F.Fab")
			(hide yes)
			(effects
				(font
					(size 1 1)
					(thickness 0.15)
				)
			)
		)
		(property "Manufacturer" "Texas Instruments"
			(at 226.728749 5.628749 0)
			(layer "F.Fab")
			(hide yes)
			(effects
				(font
					(size 1 1)
					(thickness 0.15)
				)
			)
		)
		(sheetname "USB3")
		(sheetfile "usb3.kicad_sch")
		(attr smd)
		(fp_line
			(start 0.498 -1.401)
			(end -0.5 -1.401)
			(stroke
				(width 0.15)
				(type solid)
			)
			(layer "F.SilkS")
		)
		(fp_line
			(start 0.498 1.398)
			(end -0.5 1.398)
			(stroke
				(width 0.15)
				(type solid)
			)
			(layer "F.SilkS")
		)
		(fp_circle
			(center -0.68 -1.27)
			(end -0.63 -1.27)
			(stroke
				(width 0.15)
				(type solid)
			)
			(fill solid)
			(layer "F.SilkS")
		)
		(fp_rect
			(start -0.8 -1.5)
			(end 0.8 1.499)
			(stroke
				(width 0.05)
				(type solid)
			)
			(fill none)
			(layer "F.CrtYd")
		)
		(fp_line
			(start 0.498 -1.25)
			(end -0.25 -1.25)
			(stroke
				(width 0.15)
				(type solid)
			)
			(layer "F.Fab")
		)
		(fp_line
			(start 0.498 -1.25)
			(end 0.498 1.249)
			(stroke
				(width 0.15)
				(type solid)
			)
			(layer "F.Fab")
		)
		(fp_line
			(start -0.25 -1.25)
			(end -0.5 -1)
			(stroke
				(width 0.15)
				(type solid)
			)
			(layer "F.Fab")
		)
		(fp_line
			(start -0.5 -1)
			(end -0.5 1.249)
			(stroke
				(width 0.15)
				(type solid)
			)
			(layer "F.Fab")
		)
		(fp_line
			(start -0.5 1.249)
			(end 0.498 1.249)
			(stroke
				(width 0.15)
				(type solid)
			)
			(layer "F.Fab")
		)
		(fp_text user "${REFERENCE}"
			(at -0.802 4.498 90)
			(layer "F.Fab")
			(hide yes)
			(effects
				(font
					(size 0.7 0.7)
					(thickness 0.15)
				)
				(justify left bottom)
			)
		)
		(fp_text user "License: Apache-2.0"
			(at -0.802 6.9 90)
			(layer "F.Fab")
			(hide yes)
			(effects
				(font
					(size 0.7 0.7)
					(thickness 0.15)
				)
				(justify left bottom)
			)
		)
		(fp_text user "Author: Antmicro"
			(at -0.802 5.7 90)
			(layer "F.Fab")
			(hide yes)
			(effects
				(font
					(size 0.7 0.7)
					(thickness 0.15)
				)
				(justify left bottom)
			)
		)
		(pad "1" smd roundrect
			(at -0.387 -1)
			(size 0.25 0.55)
			(layers "F.Cu" "F.Paste" "F.Mask")
			(roundrect_rratio 0.25)
			(net 366 "/USB3/USBC1_RX1_N")
			(pintype "passive")
		)
		(pad "2" smd roundrect
			(at -0.387 -0.5)
			(size 0.25 0.55)
			(layers "F.Cu" "F.Paste" "F.Mask")
			(roundrect_rratio 0.25)
			(net 368 "/USB3/USBC1_RX1_P")
			(pintype "passive")
		)
		(pad "3" smd roundrect
			(at -0.387 0)
			(size 0.4 0.55)
			(layers "F.Cu" "F.Paste" "F.Mask")
			(roundrect_rratio 0.25)
			(net 1 "GND")
			(pintype "power_in")
		)
		(pad "4" smd roundrect
			(at -0.387 0.498)
			(size 0.25 0.55)
			(layers "F.Cu" "F.Paste" "F.Mask")
			(roundrect_rratio 0.25)
			(net 265 "/USB3/USBC1_CONN_TX1_N")
			(pintype "passive")
		)
		(pad "5" smd roundrect
			(at -0.387 0.998)
			(size 0.25 0.55)
			(layers "F.Cu" "F.Paste" "F.Mask")
			(roundrect_rratio 0.25)
			(net 267 "/USB3/USBC1_CONN_TX1_P")
			(pintype "passive")
		)
		(pad "6" smd roundrect
			(at 0.385 0.998)
			(size 0.25 0.55)
			(layers "F.Cu" "F.Paste" "F.Mask")
			(roundrect_rratio 0.25)
			(net 267 "/USB3/USBC1_CONN_TX1_P")
			(pintype "passive")
		)
		(pad "7" smd roundrect
			(at 0.385 0.498)
			(size 0.25 0.55)
			(layers "F.Cu" "F.Paste" "F.Mask")
			(roundrect_rratio 0.25)
			(net 265 "/USB3/USBC1_CONN_TX1_N")
			(pintype "passive")
		)
		(pad "8" smd roundrect
			(at 0.385 0)
			(size 0.4 0.55)
			(layers "F.Cu" "F.Paste" "F.Mask")
			(roundrect_rratio 0.25)
			(net 1 "GND")
			(pintype "passive")
		)
		(pad "9" smd roundrect
			(at 0.385 -0.5)
			(size 0.25 0.55)
			(layers "F.Cu" "F.Paste" "F.Mask")
			(roundrect_rratio 0.25)
			(net 368 "/USB3/USBC1_RX1_P")
			(pintype "passive")
		)
		(pad "10" smd roundrect
			(at 0.385 -1)
			(size 0.25 0.55)
			(layers "F.Cu" "F.Paste" "F.Mask")
			(roundrect_rratio 0.25)
			(net 366 "/USB3/USBC1_RX1_N")
			(pintype "passive")
		)
	)
	(footprint "antmicro-footprints:C_0402_1005Metric"
		(layer "F.Cu")
		(at 55.54 104.87 -90)
		(descr "Capacitor SMD 0402")
		(tags "capacitor SMD 0402")
		(property "Reference" "C48"
			(at 1.08 0.39 -90)
			(layer "F.SilkS")
			(effects
				(font
					(size 0.7 0.7)
					(thickness 0.15)
				)
				(justify left bottom)
			)
		)
		(property "Value" "C_100n_0402"
			(at 0 1.4 -90)
			(layer "F.Fab")
			(effects
				(font
					(size 0.7 0.7)
					(thickness 0.15)
				)
				(justify left bottom)
			)
		)
		(property "Footprint" "antmicro-footprints:C_0402_1005Metric"
			(at 0 0 -90)
			(layer "F.Fab")
			(hide yes)
			(effects
				(font
					(size 1.27 1.27)
					(thickness 0.15)
				)
			)
		)
		(property "Datasheet" "https://www.murata.com/products/productdetail?partno=GRM155R61H104KE14%23"
			(at 0 0 -90)
			(layer "F.Fab")
			(hide yes)
			(effects
				(font
					(size 1.27 1.27)
					(thickness 0.15)
				)
			)
		)
		(property "Author" "Antmicro"
			(at -49.33 160.41 0)
			(layer "F.Fab")
			(hide yes)
			(effects
				(font
					(size 1 1)
					(thickness 0.15)
				)
			)
		)
		(property "Dielectric" "X5R"
			(at -49.33 160.41 0)
			(layer "F.Fab")
			(hide yes)
			(effects
				(font
					(size 1 1)
					(thickness 0.15)
				)
			)
		)
		(property "License" "Apache-2.0"
			(at -49.33 160.41 0)
			(layer "F.Fab")
			(hide yes)
			(effects
				(font
					(size 1 1)
					(thickness 0.15)
				)
			)
		)
		(property "MPN" "GRM155R61H104KE14D"
			(at -49.33 160.41 0)
			(layer "F.Fab")
			(hide yes)
			(effects
				(font
					(size 1 1)
					(thickness 0.15)
				)
			)
		)
		(property "Manufacturer" "Murata"
			(at -49.33 160.41 0)
			(layer "F.Fab")
			(hide yes)
			(effects
				(font
					(size 1 1)
					(thickness 0.15)
				)
			)
		)
		(property "Val" "100n"
			(at -49.33 160.41 0)
			(layer "F.Fab")
			(hide yes)
			(effects
				(font
					(size 1 1)
					(thickness 0.15)
				)
			)
		)
		(property "Voltage" "50V"
			(at -49.33 160.41 0)
			(layer "F.Fab")
			(hide yes)
			(effects
				(font
					(size 1 1)
					(thickness 0.15)
				)
			)
		)
		(sheetname "Peripherals")
		(sheetfile "peripherals.kicad_sch")
		(attr smd)
		(fp_rect
			(start -0.925 -0.47)
			(end 0.925 0.47)
			(stroke
				(width 0.05)
				(type default)
			)
			(fill none)
			(layer "F.CrtYd")
		)
		(fp_line
			(start -0.494 0.248)
			(end -0.494 -0.25)
			(stroke
				(width 0.15)
				(type solid)
			)
			(layer "F.Fab")
		)
		(fp_line
			(start 0.504 0.248)
			(end -0.494 0.248)
			(stroke
				(width 0.15)
				(type solid)
			)
			(layer "F.Fab")
		)
		(fp_line
			(start -0.494 -0.25)
			(end 0.504 -0.25)
			(stroke
				(width 0.15)
				(type solid)
			)
			(layer "F.Fab")
		)
		(fp_line
			(start 0.504 -0.25)
			(end 0.504 0.248)
			(stroke
				(width 0.15)
				(type solid)
			)
			(layer "F.Fab")
		)
		(fp_text user "Author: Antmicro"
			(at -0.932 4.17 -90)
			(layer "F.Fab")
			(hide yes)
			(effects
				(font
					(size 0.7 0.7)
					(thickness 0.15)
				)
				(justify left bottom)
			)
		)
		(fp_text user "${REFERENCE}"
			(at -0.932 3.168 -90)
			(layer "F.Fab")
			(hide yes)
			(effects
				(font
					(size 0.7 0.7)
					(thickness 0.15)
				)
				(justify left bottom)
			)
		)
		(fp_text user "License: Apache-2.0"
			(at -0.932 5.17 -90)
			(layer "F.Fab")
			(hide yes)
			(effects
				(font
					(size 0.7 0.7)
					(thickness 0.15)
				)
				(justify left bottom)
			)
		)
		(pad "1" smd roundrect
			(at -0.48 0 270)
			(size 0.59 0.64)
			(layers "F.Cu" "F.Paste" "F.Mask")
			(roundrect_rratio 0.25)
			(net 1 "GND")
			(pintype "passive")
		)
		(pad "2" smd roundrect
			(at 0.48 0 270)
			(size 0.59 0.64)
			(layers "F.Cu" "F.Paste" "F.Mask")
			(roundrect_rratio 0.25)
			(net 99 "+5V")
			(pintype "passive")
		)
	)
	(footprint "antmicro-footprints:R_0402_1005Metric"
		(layer "F.Cu")
		(at 96.15 100.4 180)
		(descr "Resistor SMD 0402")
		(tags "resistor SMD 0402")
		(property "Reference" "R161"
			(at -0.8 -0.45 180)
			(layer "F.SilkS")
			(effects
				(font
					(size 0.7 0.7)
					(thickness 0.15)
				)
				(justify left bottom)
			)
		)
		(property "Value" "R_0R_0402"
			(at 0 1.4 180)
			(layer "F.Fab")
			(effects
				(font
					(size 0.7 0.7)
					(thickness 0.15)
				)
				(justify left bottom)
			)
		)
		(property "Footprint" "antmicro-footprints:R_0402_1005Metric"
			(at 0 0 180)
			(layer "F.Fab")
			(hide yes)
			(effects
				(font
					(size 1.27 1.27)
					(thickness 0.15)
				)
			)
		)
		(property "Datasheet" "https://industrial.panasonic.com/cdbs/www-data/pdf/RDA0000/AOA0000C301.pdf"
			(at 0 0 180)
			(layer "F.Fab")
			(hide yes)
			(effects
				(font
					(size 1.27 1.27)
					(thickness 0.15)
				)
			)
		)
		(property "Author" "Antmicro"
			(at 192.3 200.8 0)
			(layer "F.Fab")
			(hide yes)
			(effects
				(font
					(size 1 1)
					(thickness 0.15)
				)
			)
		)
		(property "Current" "1A"
			(at 192.3 200.8 0)
			(layer "F.Fab")
			(hide yes)
			(effects
				(font
					(size 1 1)
					(thickness 0.15)
				)
			)
		)
		(property "License" "Apache-2.0"
			(at 192.3 200.8 0)
			(layer "F.Fab")
			(hide yes)
			(effects
				(font
					(size 1 1)
					(thickness 0.15)
				)
			)
		)
		(property "MPN" "ERJ2GE0R00X"
			(at 192.3 200.8 0)
			(layer "F.Fab")
			(hide yes)
			(effects
				(font
					(size 1 1)
					(thickness 0.15)
				)
			)
		)
		(property "Manufacturer" "Panasonic"
			(at 192.3 200.8 0)
			(layer "F.Fab")
			(hide yes)
			(effects
				(font
					(size 1 1)
					(thickness 0.15)
				)
			)
		)
		(property "Tolerance" ""
			(at 192.3 200.8 0)
			(layer "F.Fab")
			(hide yes)
			(effects
				(font
					(size 1 1)
					(thickness 0.15)
				)
			)
		)
		(property "Val" "0R"
			(at 192.3 200.8 0)
			(layer "F.Fab")
			(hide yes)
			(effects
				(font
					(size 1 1)
					(thickness 0.15)
				)
			)
		)
		(sheetname "CSI")
		(sheetfile "csi.kicad_sch")
		(attr smd)
		(fp_rect
			(start -0.925 -0.47)
			(end 0.925 0.47)
			(stroke
				(width 0.05)
				(type default)
			)
			(fill none)
			(layer "F.CrtYd")
		)
		(fp_rect
			(start -0.5 -0.25)
			(end 0.5 0.25)
			(stroke
				(width 0.15)
				(type solid)
			)
			(fill none)
			(layer "F.Fab")
		)
		(fp_text user "License: Apache-2.0"
			(at -0.95 5.169 180)
			(layer "F.Fab")
			(hide yes)
			(effects
				(font
					(size 0.7 0.7)
					(thickness 0.15)
				)
				(justify left bottom)
			)
		)
		(fp_text user "${REFERENCE}"
			(at -0.95 3.168 180)
			(layer "F.Fab")
			(hide yes)
			(effects
				(font
					(size 0.7 0.7)
					(thickness 0.15)
				)
				(justify left bottom)
			)
		)
		(fp_text user "Author: Antmicro"
			(at -0.95 4.169 180)
			(layer "F.Fab")
			(hide yes)
			(effects
				(font
					(size 0.7 0.7)
					(thickness 0.15)
				)
				(justify left bottom)
			)
		)
		(pad "1" smd roundrect
			(at -0.48 0 180)
			(size 0.59 0.64)
			(layers "F.Cu" "F.Paste" "F.Mask")
			(roundrect_rratio 0.25)
			(net 511 "/CSI/I2C_MUX_SDA")
			(pintype "passive")
		)
		(pad "2" smd roundrect
			(at 0.48 0 180)
			(size 0.59 0.64)
			(layers "F.Cu" "F.Paste" "F.Mask")
			(roundrect_rratio 0.25)
			(net 79 "SDA_CAM")
			(pintype "passive")
		)
	)
)
